(kicad_pcb
	(version 20260206)
	(generator "pcbnew")
	(generator_version "10.0")
	(general
		(thickness 1.6)
		(legacy_teardrops no)
	)
	(paper "A4")
	(title_block
		(title "dpb — 14545-sa.0730WZS0815.brd")
		(comment 1 "Honey Badger (Wiwynn) / footprints 755-757 of 1066")
	)
	(layers
		(0 "F.Cu" signal "TOP")
		(4 "In1.Cu" signal "L2GND")
		(6 "In2.Cu" signal "L3")
		(8 "In3.Cu" signal "L4VCC")
		(10 "In4.Cu" signal "L5VCC")
		(12 "In5.Cu" signal "L6")
		(14 "In6.Cu" signal "L7GND")
		(2 "B.Cu" signal "BOTTOM")
		(9 "F.Adhes" user "F.Adhesive")
		(11 "B.Adhes" user "B.Adhesive")
		(13 "F.Paste" user "Package Geometry/Pastemask Top")
		(15 "B.Paste" user "Package Geometry/Pastemask Bottom")
		(5 "F.SilkS" user "Ref Des/Silkscreen Top")
		(7 "B.SilkS" user "Ref Des/Silkscreen Bottom")
		(1 "F.Mask" user "Board Geometry/Soldermask Top")
		(3 "B.Mask" user "Board Geometry/Soldermask Bottom")
		(17 "Dwgs.User" user "User.Drawings")
		(19 "Cmts.User" user "User.Comments")
		(21 "Eco1.User" user "User.Eco1")
		(23 "Eco2.User" user "User.Eco2")
		(25 "Edge.Cuts" user "Board Geometry/Outline")
		(27 "Margin" user)
		(31 "F.CrtYd" user "Package Geometry/Place Bound Top")
		(29 "B.CrtYd" user "Package Geometry/Place Bound Bottom")
		(35 "F.Fab" user "Ref Des/Assembly Top")
		(33 "B.Fab" user "Ref Des/Assembly Bottom")
	)
	(footprint ""
		(layer "F.Cu")
		(at 227.499926 -479.67011 90)
		(property "Reference" "SKT1"
			(at 0 0 90)
			(layer "F.SilkS")
			(hide yes)
			(effects
				(font
					(size 1.27 1.27)
				)
			)
		)
		(property "Value" "SKT-SATA14P-15P-12-GP"
			(at -22.6187 8.1788 90)
			(unlocked yes)
			(layer "F.Fab")
			(hide yes)
			(effects
				(font
					(size 1.016 1.016)
					(thickness 0.1524)
				)
			)
		)
		(property "Device Type" "87945-1001"
			(at -22.6187 6.6548 90)
			(unlocked yes)
			(layer "F.Fab")
			(hide yes)
			(effects
				(font
					(size 1.016 1.016)
					(thickness 0.1524)
				)
			)
		)
		(duplicate_pad_numbers_are_jumpers no)
		(fp_line
			(start -15.3924 -5.8547)
			(end -16.3576 -5.8547)
			(stroke
				(width 0.3302)
				(type default)
			)
			(layer "F.SilkS")
		)
		(fp_line
			(start 20.4724 -5.7658)
			(end 20.4724 -2.3114)
			(stroke
				(width 0.1524)
				(type default)
			)
			(layer "F.SilkS")
		)
		(fp_line
			(start -20.4724 -5.7658)
			(end 20.4724 -5.7658)
			(stroke
				(width 0.1524)
				(type default)
			)
			(layer "F.SilkS")
		)
		(fp_line
			(start 23.7617 -2.3114)
			(end 23.7617 2.3114)
			(stroke
				(width 0.1524)
				(type default)
			)
			(layer "F.SilkS")
		)
		(fp_line
			(start 20.4724 -2.3114)
			(end 23.7617 -2.3114)
			(stroke
				(width 0.1524)
				(type default)
			)
			(layer "F.SilkS")
		)
		(fp_line
			(start -20.4724 -2.3114)
			(end -20.4724 -5.7658)
			(stroke
				(width 0.1524)
				(type default)
			)
			(layer "F.SilkS")
		)
		(fp_line
			(start -23.7617 -2.3114)
			(end -20.4724 -2.3114)
			(stroke
				(width 0.1524)
				(type default)
			)
			(layer "F.SilkS")
		)
		(fp_line
			(start 23.117556 -0.5461)
			(end 23.117556 0.5461)
			(stroke
				(width 0.3048)
				(type default)
			)
			(layer "F.SilkS")
		)
		(fp_line
			(start -20.882356 -0.5461)
			(end -20.882356 0.5461)
			(stroke
				(width 0.3048)
				(type default)
			)
			(layer "F.SilkS")
		)
		(fp_line
			(start 20.882356 0.5461)
			(end 20.882356 -0.5461)
			(stroke
				(width 0.3048)
				(type default)
			)
			(layer "F.SilkS")
		)
		(fp_line
			(start -23.117556 0.5461)
			(end -23.117556 -0.5461)
			(stroke
				(width 0.3048)
				(type default)
			)
			(layer "F.SilkS")
		)
		(fp_line
			(start 23.7617 2.3114)
			(end 20.4724 2.3114)
			(stroke
				(width 0.1524)
				(type default)
			)
			(layer "F.SilkS")
		)
		(fp_line
			(start 20.4724 2.3114)
			(end 20.4724 9.652)
			(stroke
				(width 0.1524)
				(type default)
			)
			(layer "F.SilkS")
		)
		(fp_line
			(start -20.4724 2.3114)
			(end -23.7617 2.3114)
			(stroke
				(width 0.1524)
				(type default)
			)
			(layer "F.SilkS")
		)
		(fp_line
			(start -23.7617 2.3114)
			(end -23.7617 -2.3114)
			(stroke
				(width 0.1524)
				(type default)
			)
			(layer "F.SilkS")
		)
		(fp_line
			(start 17.8435 7.9502)
			(end -17.8435 7.9502)
			(stroke
				(width 0.1524)
				(type default)
			)
			(layer "F.SilkS")
		)
		(fp_line
			(start -17.8435 7.9502)
			(end -17.8435 9.652)
			(stroke
				(width 0.1524)
				(type default)
			)
			(layer "F.SilkS")
		)
		(fp_line
			(start 20.4724 9.652)
			(end 17.8435 9.652)
			(stroke
				(width 0.1524)
				(type default)
			)
			(layer "F.SilkS")
		)
		(fp_line
			(start 17.8435 9.652)
			(end 17.8435 7.9502)
			(stroke
				(width 0.1524)
				(type default)
			)
			(layer "F.SilkS")
		)
		(fp_line
			(start -17.8435 9.652)
			(end -20.4724 9.652)
			(stroke
				(width 0.1524)
				(type default)
			)
			(layer "F.SilkS")
		)
		(fp_line
			(start -20.4724 9.652)
			(end -20.4724 2.3114)
			(stroke
				(width 0.1524)
				(type default)
			)
			(layer "F.SilkS")
		)
		(fp_arc
			(start 20.882356 -0.5461)
			(mid 21.999956 -1.6637)
			(end 23.117556 -0.5461)
			(stroke
				(width 0.3048)
				(type default)
			)
			(layer "F.SilkS")
		)
		(fp_arc
			(start -23.117556 -0.5461)
			(mid -21.999956 -1.6637)
			(end -20.882356 -0.5461)
			(stroke
				(width 0.3048)
				(type default)
			)
			(layer "F.SilkS")
		)
		(fp_arc
			(start 23.117556 0.5461)
			(mid 21.999956 1.6637)
			(end 20.882356 0.5461)
			(stroke
				(width 0.3048)
				(type default)
			)
			(layer "F.SilkS")
		)
		(fp_arc
			(start -20.882356 0.5461)
			(mid -21.999956 1.6637)
			(end -23.117556 0.5461)
			(stroke
				(width 0.3048)
				(type default)
			)
			(layer "F.SilkS")
		)
		(fp_poly
			(pts
				(xy -15.87119 -5.838698) (xy -15.23619 -6.473698) (xy -16.50619 -6.473698)
			)
			(stroke
				(width 0)
				(type default)
			)
			(fill yes)
			(layer "F.SilkS")
		)
		(fp_poly
			(pts
				(xy -20.2184 -5.5118) (xy 20.2184 -5.5118) (xy 20.2184 -2.0574) (xy 23.5077 -2.0574) (xy 23.5077 2.0574)
				(xy 20.2184 2.0574) (xy 20.2184 9.398) (xy 18.0975 9.398) (xy 18.0975 7.6962) (xy -18.0975 7.6962)
				(xy -18.0975 9.398) (xy -20.2184 9.398) (xy -20.2184 2.0574) (xy -23.5077 2.0574) (xy -23.5077 -2.0574)
				(xy -20.2184 -2.0574)
			)
			(stroke
				(width 0)
				(type default)
			)
			(fill no)
			(layer "F.CrtYd")
		)
		(fp_poly
			(pts
				(xy -20.2184 -5.5118) (xy -20.2184 -6.0198) (xy -20.7264 -6.0198) (xy -20.7264 -2.5654) (xy -24.0157 -2.5654)
				(xy -24.0157 2.5654) (xy -20.7264 2.5654) (xy -20.7264 9.906) (xy -17.5895 9.906) (xy -17.5895 8.2042)
				(xy 17.5895 8.2042) (xy 17.5895 9.906) (xy 20.7264 9.906) (xy 20.7264 2.5654) (xy 24.0157 2.5654)
				(xy 24.0157 -2.5654) (xy 20.7264 -2.5654) (xy 20.7264 -6.0198) (xy -20.21586 -6.0198) (xy -20.21586 -5.5118)
				(xy 20.2184 -5.5118) (xy 20.2184 -2.0574) (xy 23.5077 -2.0574) (xy 23.5077 2.0574) (xy 20.2184 2.0574)
				(xy 20.2184 9.398) (xy 18.0975 9.398) (xy 18.0975 7.6962) (xy -18.0975 7.6962) (xy -18.0975 9.398)
				(xy -20.2184 9.398) (xy -20.2184 2.0574) (xy -23.5077 2.0574) (xy -23.5077 -2.0574) (xy -20.2184 -2.0574)
			)
			(stroke
				(width 0)
				(type default)
			)
			(fill no)
			(layer "F.CrtYd")
		)
		(fp_poly
			(pts
				(xy -20.7264 -6.0198) (xy -20.7264 -2.5654) (xy -24.0157 -2.5654) (xy -24.0157 2.5654) (xy -20.7264 2.5654)
				(xy -20.7264 9.906) (xy -17.5895 9.906) (xy -17.5895 8.2042) (xy 17.5895 8.2042) (xy 17.5895 9.906)
				(xy 20.7264 9.906) (xy 20.7264 2.5654) (xy 24.0157 2.5654) (xy 24.0157 -2.5654) (xy 20.7264 -2.5654)
				(xy 20.7264 -6.0198)
			)
			(stroke
				(width 0)
				(type default)
			)
			(fill no)
			(layer "F.Fab")
		)
		(pad "" np_thru_hole circle
			(at -18.999962 -2.350008 90)
			(size 0.254 0.254)
			(drill 1.8542)
			(layers "*.Cu" "*.Mask")
			(clearance 1.1557)
			(thermal_gap 1.1557)
		)
		(pad "" np_thru_hole circle
			(at 18.999962 -2.350008 90)
			(size 0.254 0.254)
			(drill 1.8542)
			(layers "*.Cu" "*.Mask")
			(clearance 1.1557)
			(thermal_gap 1.1557)
		)
		(pad "H1" thru_hole oval
			(at -21.999956 0 90)
			(size 1.524 2.6162)
			(drill oval 0.8128 1.905)
			(layers "*.Cu" "*.Mask")
			(remove_unused_layers no)
			(net "GND")
			(clearance 0.1524)
			(thermal_gap 0.1524)
		)
		(pad "H2" thru_hole oval
			(at 21.999956 0 90)
			(size 1.524 2.6162)
			(drill oval 0.8128 1.905)
			(layers "*.Cu" "*.Mask")
			(remove_unused_layers no)
			(net "GND")
			(clearance 0.1524)
			(thermal_gap 0.1524)
		)
		(pad "P1" smd rect
			(at -1.89992 -4.249928 90)
			(size 0.6604 2.3876)
			(layers "F.Cu" "F.Mask" "F.Paste")
			(net "Net_75")
		)
		(pad "P2" smd rect
			(at -0.62992 -4.249928 90)
			(size 0.6604 2.3876)
			(layers "F.Cu" "F.Mask" "F.Paste")
			(net "Net_74")
		)
		(pad "P3" smd rect
			(at 0.64008 -4.249928 90)
			(size 0.6604 2.3876)
			(layers "F.Cu" "F.Mask" "F.Paste")
			(net "Net_73")
		)
		(pad "P4" smd rect
			(at 1.91008 -4.249928 90)
			(size 0.6604 2.3876)
			(layers "F.Cu" "F.Mask" "F.Paste")
			(net "GND")
		)
		(pad "P5" smd rect
			(at 3.18008 -4.249928 90)
			(size 0.6604 2.3876)
			(layers "F.Cu" "F.Mask" "F.Paste")
			(net "HDD_PRSNT_NET0")
		)
		(pad "P6" smd rect
			(at 4.45008 -4.249928 90)
			(size 0.6604 2.3876)
			(layers "F.Cu" "F.Mask" "F.Paste")
			(net "GND")
		)
		(pad "P7" smd rect
			(at 5.72008 -4.249928 90)
			(size 0.6604 2.3876)
			(layers "F.Cu" "F.Mask" "F.Paste")
			(net "5V_PRE_0")
		)
		(pad "P8" smd rect
			(at 6.99008 -4.249928 90)
			(size 0.6604 2.3876)
			(layers "F.Cu" "F.Mask" "F.Paste")
			(net "P5V_HDD0")
		)
		(pad "P9" smd rect
			(at 8.26008 -4.249928 90)
			(size 0.6604 2.3876)
			(layers "F.Cu" "F.Mask" "F.Paste")
			(net "P5V_HDD0")
		)
		(pad "P10" smd rect
			(at 9.53008 -4.249928 90)
			(size 0.6604 2.3876)
			(layers "F.Cu" "F.Mask" "F.Paste")
			(net "GND")
		)
		(pad "P11" smd rect
			(at 10.80008 -4.249928 90)
			(size 0.6604 2.3876)
			(layers "F.Cu" "F.Mask" "F.Paste")
			(net "ACT_HDD0")
		)
		(pad "P12" smd rect
			(at 12.07008 -4.249928 90)
			(size 0.6604 2.3876)
			(layers "F.Cu" "F.Mask" "F.Paste")
			(net "GND")
		)
		(pad "P13" smd rect
			(at 13.34008 -4.249928 90)
			(size 0.6604 2.3876)
			(layers "F.Cu" "F.Mask" "F.Paste")
			(net "12V_PRE_0")
		)
		(pad "P14" smd rect
			(at 14.61008 -4.249928 90)
			(size 0.6604 2.3876)
			(layers "F.Cu" "F.Mask" "F.Paste")
			(net "P12V_HDD0")
		)
		(pad "P15" smd rect
			(at 15.88008 -4.249928 90)
			(size 0.6604 2.3876)
			(layers "F.Cu" "F.Mask" "F.Paste")
			(net "P12V_HDD0")
		)
		(pad "S1" smd rect
			(at -15.86992 -4.249928 90)
			(size 0.6604 2.3876)
			(layers "F.Cu" "F.Mask" "F.Paste")
			(net "GND")
		)
		(pad "S2" smd rect
			(at -14.59992 -4.249928 90)
			(size 0.6604 2.3876)
			(layers "F.Cu" "F.Mask" "F.Paste")
			(net "SAS2X28_A_HDD0_TX_+")
		)
		(pad "S3" smd rect
			(at -13.32992 -4.249928 90)
			(size 0.6604 2.3876)
			(layers "F.Cu" "F.Mask" "F.Paste")
			(net "SAS2X28_A_HDD0_TX_-")
		)
		(pad "S4" smd rect
			(at -12.05992 -4.249928 90)
			(size 0.6604 2.3876)
			(layers "F.Cu" "F.Mask" "F.Paste")
			(net "GND")
		)
		(pad "S5" smd rect
			(at -10.78992 -4.249928 90)
			(size 0.6604 2.3876)
			(layers "F.Cu" "F.Mask" "F.Paste")
			(net "SAS2X28_DRIVE_RX_N_A0")
		)
		(pad "S6" smd rect
			(at -9.51992 -4.249928 90)
			(size 0.6604 2.3876)
			(layers "F.Cu" "F.Mask" "F.Paste")
			(net "SAS2X28_DRIVE_RX_P_A0")
		)
		(pad "S7" smd rect
			(at -8.24992 -4.249928 90)
			(size 0.6604 2.3876)
			(layers "F.Cu" "F.Mask" "F.Paste")
			(net "GND")
		)
		(pad "S8" smd rect
			(at -7.480046 -2.100072 90)
			(size 0.508 1.905)
			(layers "F.Cu" "F.Mask" "F.Paste")
			(net "GND")
		)
		(pad "S9" smd rect
			(at -6.679946 -2.100072 90)
			(size 0.508 1.905)
			(layers "F.Cu" "F.Mask" "F.Paste")
			(net "SAS2X28_B_HDD0_TX_+")
		)
		(pad "S10" smd rect
			(at -5.8801 -2.100072 90)
			(size 0.508 1.905)
			(layers "F.Cu" "F.Mask" "F.Paste")
			(net "SAS2X28_B_HDD0_TX_-")
		)
		(pad "S11" smd rect
			(at -5.08 -2.100072 90)
			(size 0.508 1.905)
			(layers "F.Cu" "F.Mask" "F.Paste")
			(net "GND")
		)
		(pad "S12" smd rect
			(at -4.2799 -2.100072 90)
			(size 0.508 1.905)
			(layers "F.Cu" "F.Mask" "F.Paste")
			(net "SAS2X28_DRIVE_RX_N_B0")
		)
		(pad "S13" smd rect
			(at -3.480054 -2.100072 90)
			(size 0.508 1.905)
			(layers "F.Cu" "F.Mask" "F.Paste")
			(net "SAS2X28_DRIVE_RX_P_B0")
		)
		(pad "S14" smd rect
			(at -2.679954 -2.100072 90)
			(size 0.508 1.905)
			(layers "F.Cu" "F.Mask" "F.Paste")
			(net "GND")
		)
		(zone
			(layers "F.Cu" "B.Cu" "In1.Cu" "In2.Cu" "In3.Cu" "In4.Cu" "In5.Cu" "In6.Cu")
			(hatch none 0.5)
			(connect_pads
				(clearance 0)
			)
			(min_thickness 0.25)
			(keepout
				(tracks not_allowed)
				(vias allowed)
				(pads allowed)
				(copperpour not_allowed)
				(footprints allowed)
			)
			(placement
				(enabled no)
				(sheetname "")
			)
			(fill
				(thermal_gap 0.5)
				(thermal_bridge_width 0.5)
				(island_removal_mode 0)
			)
			(polygon
				(pts
					(arc
						(start 226.381818 -498.670072)
						(mid 223.918018 -498.670072)
						(end 226.381818 -498.670072)
					)
				)
			)
		)
		(zone
			(layers "F.Cu" "B.Cu" "In1.Cu" "In2.Cu" "In3.Cu" "In4.Cu" "In5.Cu" "In6.Cu")
			(hatch none 0.5)
			(connect_pads
				(clearance 0)
			)
			(min_thickness 0.25)
			(keepout
				(tracks not_allowed)
				(vias allowed)
				(pads allowed)
				(copperpour not_allowed)
				(footprints allowed)
			)
			(placement
				(enabled no)
				(sheetname "")
			)
			(fill
				(thermal_gap 0.5)
				(thermal_bridge_width 0.5)
				(island_removal_mode 0)
			)
			(polygon
				(pts
					(arc
						(start 226.381818 -460.670148)
						(mid 223.918018 -460.670148)
						(end 226.381818 -460.670148)
					)
				)
			)
		)
	)
	(footprint ""
		(layer "F.Cu")
		(at 42.500042 -453.159876 180)
		(property "Reference" "LED6"
			(at 0 0 180)
			(layer "F.SilkS")
			(hide yes)
			(effects
				(font
					(size 1.27 1.27)
				)
			)
		)
		(property "Value" "LED-RB-4-GP"
			(at 5.88899 1.80848 180)
			(unlocked yes)
			(layer "F.Fab")
			(hide yes)
			(effects
				(font
					(size 1.016 1.016)
					(thickness 0.1524)
				)
			)
		)
		(property "Device Type" "LED1613-4PH20"
			(at 5.88899 0.28448 180)
			(unlocked yes)
			(layer "F.Fab")
			(hide yes)
			(effects
				(font
					(size 1.016 1.016)
					(thickness 0.1524)
				)
			)
		)
		(duplicate_pad_numbers_are_jumpers no)
		(fp_line
			(start 1.4478 0.9652)
			(end -1.4478 0.9652)
			(stroke
				(width 0.1524)
				(type default)
			)
			(layer "F.SilkS")
		)
		(fp_line
			(start 1.4478 -0.9652)
			(end 1.4478 0.9652)
			(stroke
				(width 0.1524)
				(type default)
			)
			(layer "F.SilkS")
		)
		(fp_line
			(start -1.4478 0.9652)
			(end -1.4478 -0.9652)
			(stroke
				(width 0.1524)
				(type default)
			)
			(layer "F.SilkS")
		)
		(fp_line
			(start -1.4478 0.9652)
			(end -1.4478 -0.9652)
			(stroke
				(width 0.508)
				(type default)
			)
			(layer "F.SilkS")
		)
		(fp_line
			(start -1.4478 -0.9652)
			(end 1.4478 -0.9652)
			(stroke
				(width 0.1524)
				(type default)
			)
			(layer "F.SilkS")
		)
		(fp_rect
			(start -0.8001 0.6477)
			(end 0.8001 -0.6477)
			(stroke
				(width 0)
				(type default)
			)
			(fill no)
			(layer "F.CrtYd")
		)
		(fp_poly
			(pts
				(xy -1.7018 1.2192) (xy -1.7018 -0.06223) (xy -0.8001 -0.06223) (xy -0.8001 0.6477) (xy 0.8001 0.6477)
				(xy 0.8001 -0.6477) (xy -0.8001 -0.6477) (xy -0.8001 -0.0635) (xy -1.7018 -0.0635) (xy -1.7018 -1.2192)
				(xy 1.7018 -1.2192) (xy 1.7018 1.2192)
			)
			(stroke
				(width 0)
				(type default)
			)
			(fill no)
			(layer "F.CrtYd")
		)
		(fp_rect
			(start -1.7018 1.2192)
			(end 1.7018 -1.2192)
			(stroke
				(width 0)
				(type default)
			)
			(fill no)
			(layer "F.Fab")
		)
		(pad "1" smd rect
			(at -0.73025 0.4064 180)
			(size 0.9144 0.6096)
			(layers "F.Cu" "F.Mask" "F.Paste")
			(net "DRV_ACT_NET5")
		)
		(pad "2" smd rect
			(at -0.73025 -0.4064 180)
			(size 0.9144 0.6096)
			(layers "F.Cu" "F.Mask" "F.Paste")
			(net "FLT_NET_HDD5")
		)
		(pad "3" smd rect
			(at 0.73025 -0.4064 180)
			(size 0.9144 0.6096)
			(layers "F.Cu" "F.Mask" "F.Paste")
			(net "FLT_HDD5")
		)
		(pad "4" smd rect
			(at 0.73025 0.4064 180)
			(size 0.9144 0.6096)
			(layers "F.Cu" "F.Mask" "F.Paste")
			(net "DRV_ACT_5")
		)
	)
	(footprint ""
		(layer "F.Cu")
		(at 55.244746 -25.2857 180)
		(property "Reference" "PR29"
			(at 0 0 180)
			(layer "F.SilkS")
			(hide yes)
			(effects
				(font
					(size 1.27 1.27)
				)
			)
		)
		(property "Value" "73K2R2F-GP"
			(at 0.064008 -3.993896 180)
			(unlocked yes)
			(layer "F.Fab")
			(hide yes)
			(effects
				(font
					(size 1.016 1.016)
					(thickness 0.1524)
				)
			)
		)
		(property "Device Type" "R402H16"
			(at 0.064008 -5.517896 180)
			(unlocked yes)
			(layer "F.Fab")
			(hide yes)
			(effects
				(font
					(size 1.016 1.016)
					(thickness 0.1524)
				)
			)
		)
		(duplicate_pad_numbers_are_jumpers no)
		(fp_line
			(start 0.508 -0.9398)
			(end -0.508 -0.9398)
			(stroke
				(width 0.1524)
				(type default)
			)
			(layer "F.SilkS")
		)
		(fp_line
			(start -0.508 -0.9398)
			(end -0.508 0.9398)
			(stroke
				(width 0.1524)
				(type default)
			)
			(layer "F.SilkS")
		)
		(fp_rect
			(start -0.508 0.9398)
			(end 0.508 -0.9398)
			(stroke
				(width 0)
				(type default)
			)
			(fill no)
			(layer "F.CrtYd")
		)
		(fp_rect
			(start -0.508 0.9398)
			(end 0.508 -0.9398)
			(stroke
				(width 0)
				(type default)
			)
			(fill no)
			(layer "F.Fab")
		)
		(pad "1" smd custom
			(at 0 -0.4445 180)
			(size 0.1397 0.1397)
			(layers "F.Cu" "F.Mask" "F.Paste")
			(net "P5VB_VFB")
			(options
				(clearance outline)
				(anchor circle)
			)
			(primitives
				(gr_poly
					(pts
						(arc
							(start -0.1778 -0.2794)
							(mid -0.249642 -0.249642)
							(end -0.2794 -0.1778)
						)
						(arc
							(start -0.2794 0.1778)
							(mid -0.249642 0.249642)
							(end -0.1778 0.2794)
						)
						(arc
							(start 0.1778 0.2794)
							(mid 0.249642 0.249642)
							(end 0.2794 0.1778)
						)
						(arc
							(start 0.2794 -0.1778)
							(mid 0.249642 -0.249642)
							(end 0.1778 -0.2794)
						)
					)
					(width 0)
					(fill yes)
				)
			)
		)
		(pad "2" smd custom
			(at 0 0.4445 180)
			(size 0.1397 0.1397)
			(layers "F.Cu" "F.Mask" "F.Paste")
			(net "P5VB_VFB_NET")
			(options
				(clearance outline)
				(anchor circle)
			)
			(primitives
				(gr_poly
					(pts
						(arc
							(start -0.1778 -0.2794)
							(mid -0.249642 -0.249642)
							(end -0.2794 -0.1778)
						)
						(arc
							(start -0.2794 0.1778)
							(mid -0.249642 0.249642)
							(end -0.1778 0.2794)
						)
						(arc
							(start 0.1778 0.2794)
							(mid 0.249642 0.249642)
							(end 0.2794 0.1778)
						)
						(arc
							(start 0.2794 -0.1778)
							(mid 0.249642 -0.249642)
							(end 0.1778 -0.2794)
						)
					)
					(width 0)
					(fill yes)
				)
			)
		)
	)
)
